(kicad_pcb
	(version 20241229)
	(generator "pcbnew")
	(generator_version "9.0")
	(general
		(thickness 1.62)
		(legacy_teardrops no)
	)
	(paper "A4")
	(title_block
		(title "OCuLink to 10GbE adapter")
		(date "2026-02-23")
		(rev "1.1.0")
		(company "Antmicro Ltd")
		(comment 1 "www.antmicro.com")
		(comment 9 "footprints 339-344 of 510")
	)
	(layers
		(0 "F.Cu" signal)
		(4 "In1.Cu" signal)
		(6 "In2.Cu" signal)
		(8 "In3.Cu" signal)
		(10 "In4.Cu" signal)
		(12 "In5.Cu" signal)
		(14 "In6.Cu" signal)
		(2 "B.Cu" signal)
		(9 "F.Adhes" user "F.Adhesive")
		(11 "B.Adhes" user "B.Adhesive")
		(13 "F.Paste" user)
		(15 "B.Paste" user)
		(5 "F.SilkS" user "F.Silkscreen")
		(7 "B.SilkS" user "B.Silkscreen")
		(1 "F.Mask" user)
		(3 "B.Mask" user)
		(17 "Dwgs.User" user "User.Drawings")
		(19 "Cmts.User" user "User.Comments")
		(21 "Eco1.User" user "User.Eco1")
		(23 "Eco2.User" user "User.Eco2")
		(25 "Edge.Cuts" user)
		(27 "Margin" user)
		(31 "F.CrtYd" user "F.Courtyard")
		(29 "B.CrtYd" user "B.Courtyard")
		(35 "F.Fab" user)
		(33 "B.Fab" user)
	)
	(footprint "antmicro-footprints:C_0402_1005Metric"
		(layer "B.Cu")
		(at 85.225 102 90)
		(descr "Capacitor SMD 0402")
		(tags "capacitor SMD 0402")
		(property "Reference" "C120"
			(at 9.09 -0.447343 90)
			(layer "B.SilkS")
			(effects
				(font
					(size 0.7 0.7)
					(thickness 0.15)
				)
				(justify right top mirror)
			)
		)
		(property "Value" "C_1u_25V_0402"
			(at -1.022927 -2.155213 90)
			(layer "B.Fab")
			(hide yes)
			(effects
				(font
					(size 0.7 0.7)
					(thickness 0.15)
				)
				(justify right top mirror)
			)
		)
		(property "Datasheet" "https://www.murata.com/products/productdetail?partno=GRM155R61E105KE11%23"
			(at 0 0 90)
			(layer "B.Fab")
			(hide yes)
			(effects
				(font
					(size 1.27 1.27)
					(thickness 0.15)
				)
				(justify mirror)
			)
		)
		(property "Description" "SMD Multilayer Ceramic Capacitor, 1 µF, 25 V, 0402 [1005 Metric], ± 10%, X5R, GRM Series"
			(at 0 0 90)
			(layer "B.Fab")
			(hide yes)
			(effects
				(font
					(size 1.27 1.27)
					(thickness 0.15)
				)
				(justify mirror)
			)
		)
		(property "MPN" "GRM155R61E105KE11J"
			(at 0 0 90)
			(unlocked yes)
			(layer "B.Fab")
			(hide yes)
			(effects
				(font
					(size 1 1)
					(thickness 0.15)
				)
				(justify mirror)
			)
		)
		(property "Manufacturer" "Murata"
			(at 0 0 90)
			(unlocked yes)
			(layer "B.Fab")
			(hide yes)
			(effects
				(font
					(size 1 1)
					(thickness 0.15)
				)
				(justify mirror)
			)
		)
		(property "License" "Apache-2.0"
			(at 0 0 90)
			(unlocked yes)
			(layer "B.Fab")
			(hide yes)
			(effects
				(font
					(size 1 1)
					(thickness 0.15)
				)
				(justify mirror)
			)
		)
		(property "Author" "Antmicro"
			(at 0 0 90)
			(unlocked yes)
			(layer "B.Fab")
			(hide yes)
			(effects
				(font
					(size 1 1)
					(thickness 0.15)
				)
				(justify mirror)
			)
		)
		(property "Val" "1u"
			(at 0 0 90)
			(unlocked yes)
			(layer "B.Fab")
			(hide yes)
			(effects
				(font
					(size 1 1)
					(thickness 0.15)
				)
				(justify mirror)
			)
		)
		(property "Voltage" "25V"
			(at 0 0 90)
			(unlocked yes)
			(layer "B.Fab")
			(hide yes)
			(effects
				(font
					(size 1 1)
					(thickness 0.15)
				)
				(justify mirror)
			)
		)
		(property "Dielectric" "X5R"
			(at 0 0 90)
			(unlocked yes)
			(layer "B.Fab")
			(hide yes)
			(effects
				(font
					(size 1 1)
					(thickness 0.15)
				)
				(justify mirror)
			)
		)
		(sheetname "/X710-AT2 power/")
		(sheetfile "x710-at2-power.kicad_sch")
		(attr smd)
		(fp_rect
			(start -0.925 0.47)
			(end 0.925 -0.47)
			(stroke
				(width 0.05)
				(type default)
			)
			(fill no)
			(layer "B.CrtYd")
		)
		(fp_line
			(start 0.504 -0.248)
			(end -0.494 -0.248)
			(stroke
				(width 0.15)
				(type solid)
			)
			(layer "B.Fab")
		)
		(fp_line
			(start -0.494 -0.248)
			(end -0.494 0.25)
			(stroke
				(width 0.15)
				(type solid)
			)
			(layer "B.Fab")
		)
		(fp_line
			(start 0.504 0.25)
			(end 0.504 -0.248)
			(stroke
				(width 0.15)
				(type solid)
			)
			(layer "B.Fab")
		)
		(fp_line
			(start -0.494 0.25)
			(end 0.504 0.25)
			(stroke
				(width 0.15)
				(type solid)
			)
			(layer "B.Fab")
		)
		(pad "1" smd roundrect
			(at -0.48 0 90)
			(size 0.59 0.64)
			(layers "B.Cu" "B.Mask" "B.Paste")
			(roundrect_rratio 0.25)
			(net 28 "GND")
			(pintype "passive")
		)
		(pad "2" smd roundrect
			(at 0.48 0 90)
			(size 0.59 0.64)
			(layers "B.Cu" "B.Mask" "B.Paste")
			(roundrect_rratio 0.25)
			(net 9 "VCCD")
			(pintype "passive")
		)
	)
	(footprint "antmicro-footprints:C_0402_1005Metric"
		(layer "B.Cu")
		(at 89.225 96.45 90)
		(descr "Capacitor SMD 0402")
		(tags "capacitor SMD 0402")
		(property "Reference" "C108"
			(at 11.58 -0.432343 90)
			(layer "B.SilkS")
			(effects
				(font
					(size 0.7 0.7)
					(thickness 0.15)
				)
				(justify right top mirror)
			)
		)
		(property "Value" "C_1u_25V_0402"
			(at -1.022927 -2.155213 90)
			(layer "B.Fab")
			(hide yes)
			(effects
				(font
					(size 0.7 0.7)
					(thickness 0.15)
				)
				(justify right top mirror)
			)
		)
		(property "Datasheet" "https://www.murata.com/products/productdetail?partno=GRM155R61E105KE11%23"
			(at 0 0 90)
			(layer "B.Fab")
			(hide yes)
			(effects
				(font
					(size 1.27 1.27)
					(thickness 0.15)
				)
				(justify mirror)
			)
		)
		(property "Description" "SMD Multilayer Ceramic Capacitor, 1 µF, 25 V, 0402 [1005 Metric], ± 10%, X5R, GRM Series"
			(at 0 0 90)
			(layer "B.Fab")
			(hide yes)
			(effects
				(font
					(size 1.27 1.27)
					(thickness 0.15)
				)
				(justify mirror)
			)
		)
		(property "MPN" "GRM155R61E105KE11J"
			(at 0 0 90)
			(unlocked yes)
			(layer "B.Fab")
			(hide yes)
			(effects
				(font
					(size 1 1)
					(thickness 0.15)
				)
				(justify mirror)
			)
		)
		(property "Manufacturer" "Murata"
			(at 0 0 90)
			(unlocked yes)
			(layer "B.Fab")
			(hide yes)
			(effects
				(font
					(size 1 1)
					(thickness 0.15)
				)
				(justify mirror)
			)
		)
		(property "License" "Apache-2.0"
			(at 0 0 90)
			(unlocked yes)
			(layer "B.Fab")
			(hide yes)
			(effects
				(font
					(size 1 1)
					(thickness 0.15)
				)
				(justify mirror)
			)
		)
		(property "Author" "Antmicro"
			(at 0 0 90)
			(unlocked yes)
			(layer "B.Fab")
			(hide yes)
			(effects
				(font
					(size 1 1)
					(thickness 0.15)
				)
				(justify mirror)
			)
		)
		(property "Val" "1u"
			(at 0 0 90)
			(unlocked yes)
			(layer "B.Fab")
			(hide yes)
			(effects
				(font
					(size 1 1)
					(thickness 0.15)
				)
				(justify mirror)
			)
		)
		(property "Voltage" "25V"
			(at 0 0 90)
			(unlocked yes)
			(layer "B.Fab")
			(hide yes)
			(effects
				(font
					(size 1 1)
					(thickness 0.15)
				)
				(justify mirror)
			)
		)
		(property "Dielectric" "X5R"
			(at 0 0 90)
			(unlocked yes)
			(layer "B.Fab")
			(hide yes)
			(effects
				(font
					(size 1 1)
					(thickness 0.15)
				)
				(justify mirror)
			)
		)
		(sheetname "/X710-AT2 power/")
		(sheetfile "x710-at2-power.kicad_sch")
		(attr smd)
		(fp_rect
			(start -0.925 0.47)
			(end 0.925 -0.47)
			(stroke
				(width 0.05)
				(type default)
			)
			(fill no)
			(layer "B.CrtYd")
		)
		(fp_line
			(start 0.504 -0.248)
			(end -0.494 -0.248)
			(stroke
				(width 0.15)
				(type solid)
			)
			(layer "B.Fab")
		)
		(fp_line
			(start -0.494 -0.248)
			(end -0.494 0.25)
			(stroke
				(width 0.15)
				(type solid)
			)
			(layer "B.Fab")
		)
		(fp_line
			(start 0.504 0.25)
			(end 0.504 -0.248)
			(stroke
				(width 0.15)
				(type solid)
			)
			(layer "B.Fab")
		)
		(fp_line
			(start -0.494 0.25)
			(end 0.504 0.25)
			(stroke
				(width 0.15)
				(type solid)
			)
			(layer "B.Fab")
		)
		(pad "1" smd roundrect
			(at -0.48 0 90)
			(size 0.59 0.64)
			(layers "B.Cu" "B.Mask" "B.Paste")
			(roundrect_rratio 0.25)
			(net 28 "GND")
			(pintype "passive")
		)
		(pad "2" smd roundrect
			(at 0.48 0 90)
			(size 0.59 0.64)
			(layers "B.Cu" "B.Mask" "B.Paste")
			(roundrect_rratio 0.25)
			(net 9 "VCCD")
			(pintype "passive")
		)
	)
	(footprint "antmicro-footprints:TP_SMD_0.75mm"
		(layer "B.Cu")
		(at 99.049999 108.7)
		(property "Reference" "TP2"
			(at -0.259999 2.53 90)
			(layer "B.SilkS")
			(effects
				(font
					(size 0.7 0.7)
					(thickness 0.15)
				)
				(justify right top mirror)
			)
		)
		(property "Value" "TP_0.75mm_SMD"
			(at 0 -1.2 0)
			(layer "B.Fab")
			(hide yes)
			(effects
				(font
					(size 0.7 0.7)
					(thickness 0.15)
				)
				(justify right top mirror)
			)
		)
		(property "Description" "SMT test point"
			(at 0 0 0)
			(layer "B.Fab")
			(hide yes)
			(effects
				(font
					(size 1.27 1.27)
					(thickness 0.15)
				)
				(justify mirror)
			)
		)
		(property "MPN" ""
			(at 0 0 0)
			(unlocked yes)
			(layer "B.Fab")
			(hide yes)
			(effects
				(font
					(size 1 1)
					(thickness 0.15)
				)
				(justify mirror)
			)
		)
		(property "Manufacturer" ""
			(at 0 0 0)
			(unlocked yes)
			(layer "B.Fab")
			(hide yes)
			(effects
				(font
					(size 1 1)
					(thickness 0.15)
				)
				(justify mirror)
			)
		)
		(property "Author" "Antmicro"
			(at 0 0 0)
			(unlocked yes)
			(layer "B.Fab")
			(hide yes)
			(effects
				(font
					(size 1 1)
					(thickness 0.15)
				)
				(justify mirror)
			)
		)
		(property "License" "Apache-2.0"
			(at 0 0 0)
			(unlocked yes)
			(layer "B.Fab")
			(hide yes)
			(effects
				(font
					(size 1 1)
					(thickness 0.15)
				)
				(justify mirror)
			)
		)
		(sheetname "/X710-AT2 Misc/")
		(sheetfile "x710-at2-mics.kicad_sch")
		(attr exclude_from_pos_files exclude_from_bom)
		(fp_circle
			(center 0 0)
			(end 0.475 0)
			(stroke
				(width 0.05)
				(type default)
			)
			(fill no)
			(layer "B.CrtYd")
		)
		(pad "1" smd circle
			(at 0 0)
			(size 0.75 0.75)
			(layers "B.Cu" "B.Mask")
			(net 364 "/X710-AT2 Misc/NCSI.ARB_OUT")
			(pinfunction "1")
			(pintype "passive")
		)
	)
	(footprint "antmicro-footprints:R_0402_1005Metric"
		(layer "B.Cu")
		(at 96.88 109.95)
		(descr "Resistor SMD 0402")
		(tags "resistor SMD 0402")
		(property "Reference" "R71"
			(at -2.96 -0.25 0)
			(layer "B.SilkS")
			(effects
				(font
					(size 0.7 0.7)
					(thickness 0.15)
				)
				(justify right top mirror)
			)
		)
		(property "Value" "R_0R_0402"
			(at -1.011843 -1.772046 0)
			(layer "B.Fab")
			(hide yes)
			(effects
				(font
					(size 0.7 0.7)
					(thickness 0.15)
				)
				(justify right top mirror)
			)
		)
		(property "Datasheet" "https://industrial.panasonic.com/cdbs/www-data/pdf/RDA0000/AOA0000C301.pdf"
			(at 0 0 0)
			(layer "B.Fab")
			(hide yes)
			(effects
				(font
					(size 1.27 1.27)
					(thickness 0.15)
				)
				(justify mirror)
			)
		)
		(property "Description" "SMD Chip Resistor, Jumper, 0 ohm, 100 mW, 0402 [1005 Metric], Thick Film, General Purpose"
			(at 0 0 0)
			(layer "B.Fab")
			(hide yes)
			(effects
				(font
					(size 1.27 1.27)
					(thickness 0.15)
				)
				(justify mirror)
			)
		)
		(property "MPN" "ERJ2GE0R00X"
			(at 0 0 0)
			(unlocked yes)
			(layer "B.Fab")
			(hide yes)
			(effects
				(font
					(size 1 1)
					(thickness 0.15)
				)
				(justify mirror)
			)
		)
		(property "Manufacturer" "Panasonic"
			(at 0 0 0)
			(unlocked yes)
			(layer "B.Fab")
			(hide yes)
			(effects
				(font
					(size 1 1)
					(thickness 0.15)
				)
				(justify mirror)
			)
		)
		(property "License" "Apache-2.0"
			(at 0 0 0)
			(unlocked yes)
			(layer "B.Fab")
			(hide yes)
			(effects
				(font
					(size 1 1)
					(thickness 0.15)
				)
				(justify mirror)
			)
		)
		(property "Author" "Antmicro"
			(at 0 0 0)
			(unlocked yes)
			(layer "B.Fab")
			(hide yes)
			(effects
				(font
					(size 1 1)
					(thickness 0.15)
				)
				(justify mirror)
			)
		)
		(property "Val" "0R"
			(at 0 0 0)
			(unlocked yes)
			(layer "B.Fab")
			(hide yes)
			(effects
				(font
					(size 1 1)
					(thickness 0.15)
				)
				(justify mirror)
			)
		)
		(property "Tolerance" "~"
			(at 0 0 0)
			(unlocked yes)
			(layer "B.Fab")
			(hide yes)
			(effects
				(font
					(size 1 1)
					(thickness 0.15)
				)
				(justify mirror)
			)
		)
		(property "Current" "1A"
			(at 0 0 0)
			(unlocked yes)
			(layer "B.Fab")
			(hide yes)
			(effects
				(font
					(size 1 1)
					(thickness 0.15)
				)
				(justify mirror)
			)
		)
		(sheetname "/X710-AT2 10GbE/")
		(sheetfile "x710-at2-10gbe.kicad_sch")
		(attr smd)
		(fp_rect
			(start -0.925 0.47)
			(end 0.925 -0.47)
			(stroke
				(width 0.05)
				(type default)
			)
			(fill no)
			(layer "B.CrtYd")
		)
		(fp_rect
			(start -0.5 0.25)
			(end 0.5 -0.25)
			(stroke
				(width 0.15)
				(type solid)
			)
			(fill no)
			(layer "B.Fab")
		)
		(pad "1" smd roundrect
			(at -0.48 0)
			(size 0.59 0.64)
			(layers "B.Cu" "B.Mask" "B.Paste")
			(roundrect_rratio 0.25)
			(net 287 "/X710-AT2 10GbE/~{P1_INT}")
			(pintype "passive")
		)
		(pad "2" smd roundrect
			(at 0.48 0)
			(size 0.59 0.64)
			(layers "B.Cu" "B.Mask" "B.Paste")
			(roundrect_rratio 0.25)
			(net 286 "/X710-AT2 10GbE/~{P1_INT_R}")
			(pintype "passive")
		)
	)
	(footprint "antmicro-footprints:C_0402_1005Metric"
		(layer "B.Cu")
		(at 74 98.65)
		(descr "Capacitor SMD 0402")
		(tags "capacitor SMD 0402")
		(property "Reference" "C211"
			(at -0.85 0.45 0)
			(layer "B.SilkS")
			(effects
				(font
					(size 0.7 0.7)
					(thickness 0.15)
				)
				(justify left bottom mirror)
			)
		)
		(property "Value" "C_1u_25V_0402"
			(at -1.022927 -2.155213 0)
			(layer "B.Fab")
			(hide yes)
			(effects
				(font
					(size 0.7 0.7)
					(thickness 0.15)
				)
				(justify right top mirror)
			)
		)
		(property "Datasheet" "https://www.murata.com/products/productdetail?partno=GRM155R61E105KE11%23"
			(at 0 0 0)
			(layer "B.Fab")
			(hide yes)
			(effects
				(font
					(size 1.27 1.27)
					(thickness 0.15)
				)
				(justify mirror)
			)
		)
		(property "Description" "SMD Multilayer Ceramic Capacitor, 1 µF, 25 V, 0402 [1005 Metric], ± 10%, X5R, GRM Series"
			(at 0 0 0)
			(layer "B.Fab")
			(hide yes)
			(effects
				(font
					(size 1.27 1.27)
					(thickness 0.15)
				)
				(justify mirror)
			)
		)
		(property "MPN" "GRM155R61E105KE11J"
			(at 0 0 0)
			(unlocked yes)
			(layer "B.Fab")
			(hide yes)
			(effects
				(font
					(size 1 1)
					(thickness 0.15)
				)
				(justify mirror)
			)
		)
		(property "Manufacturer" "Murata"
			(at 0 0 0)
			(unlocked yes)
			(layer "B.Fab")
			(hide yes)
			(effects
				(font
					(size 1 1)
					(thickness 0.15)
				)
				(justify mirror)
			)
		)
		(property "License" "Apache-2.0"
			(at 0 0 0)
			(unlocked yes)
			(layer "B.Fab")
			(hide yes)
			(effects
				(font
					(size 1 1)
					(thickness 0.15)
				)
				(justify mirror)
			)
		)
		(property "Author" "Antmicro"
			(at 0 0 0)
			(unlocked yes)
			(layer "B.Fab")
			(hide yes)
			(effects
				(font
					(size 1 1)
					(thickness 0.15)
				)
				(justify mirror)
			)
		)
		(property "Val" "1u"
			(at 0 0 0)
			(unlocked yes)
			(layer "B.Fab")
			(hide yes)
			(effects
				(font
					(size 1 1)
					(thickness 0.15)
				)
				(justify mirror)
			)
		)
		(property "Voltage" "25V"
			(at 0 0 0)
			(unlocked yes)
			(layer "B.Fab")
			(hide yes)
			(effects
				(font
					(size 1 1)
					(thickness 0.15)
				)
				(justify mirror)
			)
		)
		(property "Dielectric" "X5R"
			(at 0 0 0)
			(unlocked yes)
			(layer "B.Fab")
			(hide yes)
			(effects
				(font
					(size 1 1)
					(thickness 0.15)
				)
				(justify mirror)
			)
		)
		(sheetname "/X710-AT2 Misc/")
		(sheetfile "x710-at2-mics.kicad_sch")
		(attr smd)
		(fp_rect
			(start -0.925 0.47)
			(end 0.925 -0.47)
			(stroke
				(width 0.05)
				(type default)
			)
			(fill no)
			(layer "B.CrtYd")
		)
		(fp_line
			(start -0.494 -0.248)
			(end -0.494 0.25)
			(stroke
				(width 0.15)
				(type solid)
			)
			(layer "B.Fab")
		)
		(fp_line
			(start -0.494 0.25)
			(end 0.504 0.25)
			(stroke
				(width 0.15)
				(type solid)
			)
			(layer "B.Fab")
		)
		(fp_line
			(start 0.504 -0.248)
			(end -0.494 -0.248)
			(stroke
				(width 0.15)
				(type solid)
			)
			(layer "B.Fab")
		)
		(fp_line
			(start 0.504 0.25)
			(end 0.504 -0.248)
			(stroke
				(width 0.15)
				(type solid)
			)
			(layer "B.Fab")
		)
		(pad "1" smd roundrect
			(at -0.48 0)
			(size 0.59 0.64)
			(layers "B.Cu" "B.Mask" "B.Paste")
			(roundrect_rratio 0.25)
			(net 28 "GND")
			(pintype "passive")
		)
		(pad "2" smd roundrect
			(at 0.48 0)
			(size 0.59 0.64)
			(layers "B.Cu" "B.Mask" "B.Paste")
			(roundrect_rratio 0.25)
			(net 47 "/X710-AT2 Misc/POR_BYPASS")
			(pintype "passive")
		)
	)
	(footprint "antmicro-footprints:R_0402_1005Metric"
		(layer "B.Cu")
		(at 82.225 94.6 90)
		(descr "Resistor SMD 0402")
		(tags "resistor SMD 0402")
		(property "Reference" "R140"
			(at 12.5 -0.462343 90)
			(layer "B.SilkS")
			(effects
				(font
					(size 0.7 0.7)
					(thickness 0.15)
				)
				(justify right top mirror)
			)
		)
		(property "Value" "R_100R_0402"
			(at -1.011843 -1.772046 90)
			(layer "B.Fab")
			(hide yes)
			(effects
				(font
					(size 0.7 0.7)
					(thickness 0.15)
				)
				(justify right top mirror)
			)
		)
		(property "Datasheet" "https://www.bourns.com/docs/product-datasheets/cr.pdf"
			(at 0 0 90)
			(layer "B.Fab")
			(hide yes)
			(effects
				(font
					(size 1.27 1.27)
					(thickness 0.15)
				)
				(justify mirror)
			)
		)
		(property "Description" "SMD Chip Resistor, 100 ohm, ± 1%, 62.5 mW, 0402 [1005 Metric], Thick Film, General Purpose"
			(at 0 0 90)
			(layer "B.Fab")
			(hide yes)
			(effects
				(font
					(size 1.27 1.27)
					(thickness 0.15)
				)
				(justify mirror)
			)
		)
		(property "MPN" "CR0402-FX-1000GLF"
			(at 0 0 90)
			(unlocked yes)
			(layer "B.Fab")
			(hide yes)
			(effects
				(font
					(size 1 1)
					(thickness 0.15)
				)
				(justify mirror)
			)
		)
		(property "Manufacturer" "Bourns"
			(at 0 0 90)
			(unlocked yes)
			(layer "B.Fab")
			(hide yes)
			(effects
				(font
					(size 1 1)
					(thickness 0.15)
				)
				(justify mirror)
			)
		)
		(property "License" "Apache-2.0"
			(at 0 0 90)
			(unlocked yes)
			(layer "B.Fab")
			(hide yes)
			(effects
				(font
					(size 1 1)
					(thickness 0.15)
				)
				(justify mirror)
			)
		)
		(property "Author" "Antmicro"
			(at 0 0 90)
			(unlocked yes)
			(layer "B.Fab")
			(hide yes)
			(effects
				(font
					(size 1 1)
					(thickness 0.15)
				)
				(justify mirror)
			)
		)
		(property "Val" "100R"
			(at 0 0 90)
			(unlocked yes)
			(layer "B.Fab")
			(hide yes)
			(effects
				(font
					(size 1 1)
					(thickness 0.15)
				)
				(justify mirror)
			)
		)
		(property "Tolerance" "1%"
			(at 0 0 90)
			(unlocked yes)
			(layer "B.Fab")
			(hide yes)
			(effects
				(font
					(size 1 1)
					(thickness 0.15)
				)
				(justify mirror)
			)
		)
		(sheetname "/X710-AT2 RSVD/")
		(sheetfile "x710-at2-rsvd.kicad_sch")
		(attr smd)
		(fp_rect
			(start -0.925 0.47)
			(end 0.925 -0.47)
			(stroke
				(width 0.05)
				(type default)
			)
			(fill no)
			(layer "B.CrtYd")
		)
		(fp_rect
			(start -0.5 0.25)
			(end 0.5 -0.25)
			(stroke
				(width 0.15)
				(type solid)
			)
			(fill no)
			(layer "B.Fab")
		)
		(pad "1" smd roundrect
			(at -0.48 0 90)
			(size 0.59 0.64)
			(layers "B.Cu" "B.Mask" "B.Paste")
			(roundrect_rratio 0.25)
			(net 28 "GND")
			(pintype "passive")
		)
		(pad "2" smd roundrect
			(at 0.48 0 90)
			(size 0.59 0.64)
			(layers "B.Cu" "B.Mask" "B.Paste")
			(roundrect_rratio 0.25)
			(net 128 "/X710-AT2 RSVD/RSVDY18_VSS")
			(pintype "passive")
		)
	)
)
